(kicad_pcb
	(version 20260206)
	(generator "pcbnew")
	(generator_version "10.0")
	(general
		(thickness 1.6)
		(legacy_teardrops no)
	)
	(paper "A4")
	(title_block
		(title "04192023_DAF0TMB3IC0_F0TG_MB_C_brd_V02_OCP.brd")
		(comment 1 "Grand Teton / footprints 8105-8111 of 8354")
	)
	(layers
		(0 "F.Cu" signal "TOP")
		(4 "In1.Cu" signal "GND")
		(6 "In2.Cu" signal "IN1")
		(8 "In3.Cu" signal "GND1")
		(10 "In4.Cu" signal "IN2")
		(12 "In5.Cu" signal "GND2")
		(14 "In6.Cu" signal "IN3")
		(16 "In7.Cu" signal "GND3")
		(18 "In8.Cu" signal "VCC")
		(20 "In9.Cu" signal "VCC1")
		(22 "In10.Cu" signal "GND4")
		(24 "In11.Cu" signal "IN4")
		(26 "In12.Cu" signal "GND5")
		(28 "In13.Cu" signal "IN5")
		(30 "In14.Cu" signal "GND6")
		(32 "In15.Cu" signal "IN6")
		(34 "In16.Cu" signal "GND7")
		(2 "B.Cu" signal "BOTTOM")
		(9 "F.Adhes" user "F.Adhesive")
		(11 "B.Adhes" user "B.Adhesive")
		(13 "F.Paste" user "Package Geometry/Pastemask Top")
		(15 "B.Paste" user "Package Geometry/Pastemask Bottom")
		(5 "F.SilkS" user "Ref Des/Silkscreen Top")
		(7 "B.SilkS" user "Ref Des/Silkscreen Bottom")
		(1 "F.Mask" user "Board Geometry/Soldermask Top")
		(3 "B.Mask" user "Board Geometry/Soldermask Bottom")
		(17 "Dwgs.User" user "User.Drawings")
		(19 "Cmts.User" user "User.Comments")
		(21 "Eco1.User" user "User.Eco1")
		(23 "Eco2.User" user "User.Eco2")
		(25 "Edge.Cuts" user "Board Geometry/Outline")
		(27 "Margin" user)
		(31 "F.CrtYd" user "Package Geometry/Place Bound Top")
		(29 "B.CrtYd" user "Package Geometry/Place Bound Bottom")
		(35 "F.Fab" user "Ref Des/Assembly Top")
		(33 "B.Fab" user "Ref Des/Assembly Bottom")
	)
	(footprint ""
		(layer "B.Cu")
		(at 422.373044 -398.942052 90)
		(property "Reference" "C988"
			(at 0 0 90)
			(layer "B.SilkS")
			(hide yes)
			(effects
				(font
					(size 1.27 1.27)
				)
				(justify mirror)
			)
		)
		(property "Value" ""
			(at 0 0 90)
			(layer "B.Fab")
			(effects
				(font
					(size 1.27 1.27)
				)
				(justify mirror)
			)
		)
		(duplicate_pad_numbers_are_jumpers no)
		(fp_line
			(start 0.7874 -0.4064)
			(end -0.7874 -0.4064)
			(stroke
				(width 0.1524)
				(type default)
			)
			(layer "B.SilkS")
		)
		(fp_line
			(start -0.7874 -0.4064)
			(end -0.7874 0.4064)
			(stroke
				(width 0.1524)
				(type default)
			)
			(layer "B.SilkS")
		)
		(fp_line
			(start 0.7874 0.4064)
			(end 0.7874 -0.4064)
			(stroke
				(width 0.1524)
				(type default)
			)
			(layer "B.SilkS")
		)
		(fp_line
			(start -0.7874 0.4064)
			(end 0.7874 0.4064)
			(stroke
				(width 0.1524)
				(type default)
			)
			(layer "B.SilkS")
		)
		(fp_line
			(start 0.67945 -0.305054)
			(end 0.12065 -0.305054)
			(stroke
				(width 0.1)
				(type default)
			)
			(layer "B.Fab")
		)
		(fp_line
			(start 0.12065 -0.305054)
			(end 0.12065 -0.2794)
			(stroke
				(width 0.1)
				(type default)
			)
			(layer "B.Fab")
		)
		(fp_line
			(start -0.12065 -0.3048)
			(end -0.67945 -0.3048)
			(stroke
				(width 0.1)
				(type default)
			)
			(layer "B.Fab")
		)
		(fp_line
			(start -0.67945 -0.3048)
			(end -0.67945 0.3048)
			(stroke
				(width 0.1)
				(type default)
			)
			(layer "B.Fab")
		)
		(fp_line
			(start 0.12065 -0.2794)
			(end -0.12065 -0.2794)
			(stroke
				(width 0.1)
				(type default)
			)
			(layer "B.Fab")
		)
		(fp_line
			(start -0.12065 -0.2794)
			(end -0.12065 -0.3048)
			(stroke
				(width 0.1)
				(type default)
			)
			(layer "B.Fab")
		)
		(fp_line
			(start 0.12065 0.2794)
			(end 0.12065 0.3048)
			(stroke
				(width 0.1)
				(type default)
			)
			(layer "B.Fab")
		)
		(fp_line
			(start -0.120396 0.2794)
			(end 0.12065 0.2794)
			(stroke
				(width 0.1)
				(type default)
			)
			(layer "B.Fab")
		)
		(fp_line
			(start 0.67945 0.3048)
			(end 0.67945 -0.305054)
			(stroke
				(width 0.1)
				(type default)
			)
			(layer "B.Fab")
		)
		(fp_line
			(start 0.12065 0.3048)
			(end 0.67945 0.3048)
			(stroke
				(width 0.1)
				(type default)
			)
			(layer "B.Fab")
		)
		(fp_line
			(start -0.120396 0.3048)
			(end -0.120396 0.2794)
			(stroke
				(width 0.1)
				(type default)
			)
			(layer "B.Fab")
		)
		(fp_line
			(start -0.67945 0.3048)
			(end -0.120396 0.3048)
			(stroke
				(width 0.1)
				(type default)
			)
			(layer "B.Fab")
		)
		(pad "1" smd circle
			(at 0.40005 0 270)
			(size 0 0)
			(layers "B.Cu" "B.Mask" "B.Paste")
			(net "P0V9_CPU0_RT2_2A")
		)
		(pad "2" smd circle
			(at -0.40005 0 270)
			(size 0 0)
			(layers "B.Cu" "B.Mask" "B.Paste")
			(net "GND")
		)
	)
	(footprint ""
		(layer "B.Cu")
		(at 309.81777 -350.65589 -90)
		(property "Reference" "PC123_4"
			(at 0 0 90)
			(layer "B.SilkS")
			(hide yes)
			(effects
				(font
					(size 1.27 1.27)
				)
				(justify mirror)
			)
		)
		(property "Value" ""
			(at 0 0 90)
			(layer "B.Fab")
			(effects
				(font
					(size 1.27 1.27)
				)
				(justify mirror)
			)
		)
		(duplicate_pad_numbers_are_jumpers no)
		(fp_line
			(start -1.524 0.762)
			(end 1.524 0.762)
			(stroke
				(width 0.1524)
				(type default)
			)
			(layer "B.SilkS")
		)
		(fp_line
			(start 1.524 0.762)
			(end 1.524 -0.762)
			(stroke
				(width 0.1524)
				(type default)
			)
			(layer "B.SilkS")
		)
		(fp_line
			(start -1.524 -0.762)
			(end -1.524 0.762)
			(stroke
				(width 0.1524)
				(type default)
			)
			(layer "B.SilkS")
		)
		(fp_line
			(start 1.524 -0.762)
			(end -1.524 -0.762)
			(stroke
				(width 0.1524)
				(type default)
			)
			(layer "B.SilkS")
		)
		(fp_line
			(start -1.1049 0.724916)
			(end -1.1049 -0.724916)
			(stroke
				(width 0.1)
				(type default)
			)
			(layer "B.Fab")
		)
		(fp_line
			(start 1.1049 0.724916)
			(end -1.1049 0.724916)
			(stroke
				(width 0.1)
				(type default)
			)
			(layer "B.Fab")
		)
		(fp_line
			(start -1.1049 -0.724916)
			(end 1.1049 -0.724916)
			(stroke
				(width 0.1)
				(type default)
			)
			(layer "B.Fab")
		)
		(fp_line
			(start 1.1049 -0.724916)
			(end 1.1049 0.724916)
			(stroke
				(width 0.1)
				(type default)
			)
			(layer "B.Fab")
		)
		(pad "1" smd rect
			(at 0.889 0 270)
			(size 1.016 1.27)
			(layers "B.Cu" "B.Mask" "B.Paste")
			(net "SW_P12V_AUX_PVDDCR_CPU1_P0_FLT")
		)
		(pad "2" smd rect
			(at -0.889 0 270)
			(size 1.016 1.27)
			(layers "B.Cu" "B.Mask" "B.Paste")
			(net "GND")
		)
	)
	(footprint ""
		(layer "B.Cu")
		(at 370.408454 -261.046976)
		(property "Reference" "C2529"
			(at 0 0 0)
			(layer "B.SilkS")
			(hide yes)
			(effects
				(font
					(size 1.27 1.27)
				)
				(justify mirror)
			)
		)
		(property "Value" ""
			(at 0 0 0)
			(layer "B.Fab")
			(effects
				(font
					(size 1.27 1.27)
				)
				(justify mirror)
			)
		)
		(duplicate_pad_numbers_are_jumpers no)
		(fp_line
			(start -0.7874 -0.4064)
			(end -0.7874 0.4064)
			(stroke
				(width 0.1524)
				(type default)
			)
			(layer "B.SilkS")
		)
		(fp_line
			(start -0.7874 0.4064)
			(end 0.7874 0.4064)
			(stroke
				(width 0.1524)
				(type default)
			)
			(layer "B.SilkS")
		)
		(fp_line
			(start 0.7874 -0.4064)
			(end -0.7874 -0.4064)
			(stroke
				(width 0.1524)
				(type default)
			)
			(layer "B.SilkS")
		)
		(fp_line
			(start 0.7874 0.4064)
			(end 0.7874 -0.4064)
			(stroke
				(width 0.1524)
				(type default)
			)
			(layer "B.SilkS")
		)
		(fp_line
			(start -0.67945 -0.3048)
			(end -0.67945 0.3048)
			(stroke
				(width 0.1)
				(type default)
			)
			(layer "B.Fab")
		)
		(fp_line
			(start -0.67945 0.3048)
			(end -0.120396 0.3048)
			(stroke
				(width 0.1)
				(type default)
			)
			(layer "B.Fab")
		)
		(fp_line
			(start -0.12065 -0.3048)
			(end -0.67945 -0.3048)
			(stroke
				(width 0.1)
				(type default)
			)
			(layer "B.Fab")
		)
		(fp_line
			(start -0.12065 -0.2794)
			(end -0.12065 -0.3048)
			(stroke
				(width 0.1)
				(type default)
			)
			(layer "B.Fab")
		)
		(fp_line
			(start -0.120396 0.2794)
			(end 0.12065 0.2794)
			(stroke
				(width 0.1)
				(type default)
			)
			(layer "B.Fab")
		)
		(fp_line
			(start -0.120396 0.3048)
			(end -0.120396 0.2794)
			(stroke
				(width 0.1)
				(type default)
			)
			(layer "B.Fab")
		)
		(fp_line
			(start 0.12065 -0.305054)
			(end 0.12065 -0.2794)
			(stroke
				(width 0.1)
				(type default)
			)
			(layer "B.Fab")
		)
		(fp_line
			(start 0.12065 -0.2794)
			(end -0.12065 -0.2794)
			(stroke
				(width 0.1)
				(type default)
			)
			(layer "B.Fab")
		)
		(fp_line
			(start 0.12065 0.2794)
			(end 0.12065 0.3048)
			(stroke
				(width 0.1)
				(type default)
			)
			(layer "B.Fab")
		)
		(fp_line
			(start 0.12065 0.3048)
			(end 0.67945 0.3048)
			(stroke
				(width 0.1)
				(type default)
			)
			(layer "B.Fab")
		)
		(fp_line
			(start 0.67945 -0.305054)
			(end 0.12065 -0.305054)
			(stroke
				(width 0.1)
				(type default)
			)
			(layer "B.Fab")
		)
		(fp_line
			(start 0.67945 0.3048)
			(end 0.67945 -0.305054)
			(stroke
				(width 0.1)
				(type default)
			)
			(layer "B.Fab")
		)
		(pad "1" smd circle
			(at 0.40005 0 180)
			(size 0 0)
			(layers "B.Cu" "B.Mask" "B.Paste")
			(net "PVDDCR_SOC_P0")
		)
		(pad "2" smd circle
			(at -0.40005 0 180)
			(size 0 0)
			(layers "B.Cu" "B.Mask" "B.Paste")
			(net "GND")
		)
	)
	(footprint ""
		(layer "B.Cu")
		(at 117.388386 -251.781564)
		(property "Reference" "C2451"
			(at 0 0 0)
			(layer "B.SilkS")
			(hide yes)
			(effects
				(font
					(size 1.27 1.27)
				)
				(justify mirror)
			)
		)
		(property "Value" ""
			(at 0 0 0)
			(layer "B.Fab")
			(effects
				(font
					(size 1.27 1.27)
				)
				(justify mirror)
			)
		)
		(duplicate_pad_numbers_are_jumpers no)
		(fp_line
			(start -0.7874 -0.4064)
			(end -0.7874 0.4064)
			(stroke
				(width 0.1524)
				(type default)
			)
			(layer "B.SilkS")
		)
		(fp_line
			(start -0.7874 0.4064)
			(end 0.7874 0.4064)
			(stroke
				(width 0.1524)
				(type default)
			)
			(layer "B.SilkS")
		)
		(fp_line
			(start 0.7874 -0.4064)
			(end -0.7874 -0.4064)
			(stroke
				(width 0.1524)
				(type default)
			)
			(layer "B.SilkS")
		)
		(fp_line
			(start 0.7874 0.4064)
			(end 0.7874 -0.4064)
			(stroke
				(width 0.1524)
				(type default)
			)
			(layer "B.SilkS")
		)
		(fp_line
			(start -0.67945 -0.3048)
			(end -0.67945 0.3048)
			(stroke
				(width 0.1)
				(type default)
			)
			(layer "B.Fab")
		)
		(fp_line
			(start -0.67945 0.3048)
			(end -0.120396 0.3048)
			(stroke
				(width 0.1)
				(type default)
			)
			(layer "B.Fab")
		)
		(fp_line
			(start -0.12065 -0.3048)
			(end -0.67945 -0.3048)
			(stroke
				(width 0.1)
				(type default)
			)
			(layer "B.Fab")
		)
		(fp_line
			(start -0.12065 -0.2794)
			(end -0.12065 -0.3048)
			(stroke
				(width 0.1)
				(type default)
			)
			(layer "B.Fab")
		)
		(fp_line
			(start -0.120396 0.2794)
			(end 0.12065 0.2794)
			(stroke
				(width 0.1)
				(type default)
			)
			(layer "B.Fab")
		)
		(fp_line
			(start -0.120396 0.3048)
			(end -0.120396 0.2794)
			(stroke
				(width 0.1)
				(type default)
			)
			(layer "B.Fab")
		)
		(fp_line
			(start 0.12065 -0.305054)
			(end 0.12065 -0.2794)
			(stroke
				(width 0.1)
				(type default)
			)
			(layer "B.Fab")
		)
		(fp_line
			(start 0.12065 -0.2794)
			(end -0.12065 -0.2794)
			(stroke
				(width 0.1)
				(type default)
			)
			(layer "B.Fab")
		)
		(fp_line
			(start 0.12065 0.2794)
			(end 0.12065 0.3048)
			(stroke
				(width 0.1)
				(type default)
			)
			(layer "B.Fab")
		)
		(fp_line
			(start 0.12065 0.3048)
			(end 0.67945 0.3048)
			(stroke
				(width 0.1)
				(type default)
			)
			(layer "B.Fab")
		)
		(fp_line
			(start 0.67945 -0.305054)
			(end 0.12065 -0.305054)
			(stroke
				(width 0.1)
				(type default)
			)
			(layer "B.Fab")
		)
		(fp_line
			(start 0.67945 0.3048)
			(end 0.67945 -0.305054)
			(stroke
				(width 0.1)
				(type default)
			)
			(layer "B.Fab")
		)
		(pad "1" smd circle
			(at 0.40005 0 180)
			(size 0 0)
			(layers "B.Cu" "B.Mask" "B.Paste")
			(net "PVDDCR_SOC_P1")
		)
		(pad "2" smd circle
			(at -0.40005 0 180)
			(size 0 0)
			(layers "B.Cu" "B.Mask" "B.Paste")
			(net "GND")
		)
	)
	(footprint ""
		(layer "B.Cu")
		(at 449.789296 -52.846986 -90)
		(property "Reference" "PC571"
			(at 0 0 90)
			(layer "B.SilkS")
			(hide yes)
			(effects
				(font
					(size 1.27 1.27)
				)
				(justify mirror)
			)
		)
		(property "Value" ""
			(at 0 0 90)
			(layer "B.Fab")
			(effects
				(font
					(size 1.27 1.27)
				)
				(justify mirror)
			)
		)
		(duplicate_pad_numbers_are_jumpers no)
		(fp_line
			(start -1.524 0.762)
			(end 1.524 0.762)
			(stroke
				(width 0.1524)
				(type default)
			)
			(layer "B.SilkS")
		)
		(fp_line
			(start 1.524 0.762)
			(end 1.524 -0.762)
			(stroke
				(width 0.1524)
				(type default)
			)
			(layer "B.SilkS")
		)
		(fp_line
			(start -1.524 -0.762)
			(end -1.524 0.762)
			(stroke
				(width 0.1524)
				(type default)
			)
			(layer "B.SilkS")
		)
		(fp_line
			(start 1.524 -0.762)
			(end -1.524 -0.762)
			(stroke
				(width 0.1524)
				(type default)
			)
			(layer "B.SilkS")
		)
		(fp_line
			(start -1.1049 0.724916)
			(end -1.1049 -0.724916)
			(stroke
				(width 0.1)
				(type default)
			)
			(layer "B.Fab")
		)
		(fp_line
			(start 1.1049 0.724916)
			(end -1.1049 0.724916)
			(stroke
				(width 0.1)
				(type default)
			)
			(layer "B.Fab")
		)
		(fp_line
			(start -1.1049 -0.724916)
			(end 1.1049 -0.724916)
			(stroke
				(width 0.1)
				(type default)
			)
			(layer "B.Fab")
		)
		(fp_line
			(start 1.1049 -0.724916)
			(end 1.1049 0.724916)
			(stroke
				(width 0.1)
				(type default)
			)
			(layer "B.Fab")
		)
		(pad "1" smd rect
			(at 0.889 0 270)
			(size 1.016 1.27)
			(layers "B.Cu" "B.Mask" "B.Paste")
			(net "SW_P3V3_AUX_FLT")
		)
		(pad "2" smd rect
			(at -0.889 0 270)
			(size 1.016 1.27)
			(layers "B.Cu" "B.Mask" "B.Paste")
			(net "GND")
		)
	)
	(footprint ""
		(layer "B.Cu")
		(at 117.141244 -415.9123 -90)
		(property "Reference" "R3504"
			(at 0 0 90)
			(layer "B.SilkS")
			(hide yes)
			(effects
				(font
					(size 1.27 1.27)
				)
				(justify mirror)
			)
		)
		(property "Value" ""
			(at 0 0 90)
			(layer "B.Fab")
			(effects
				(font
					(size 1.27 1.27)
				)
				(justify mirror)
			)
		)
		(duplicate_pad_numbers_are_jumpers no)
		(fp_line
			(start -0.7874 0.4064)
			(end 0.7874 0.4064)
			(stroke
				(width 0.1524)
				(type default)
			)
			(layer "B.SilkS")
		)
		(fp_line
			(start 0.7874 0.4064)
			(end 0.7874 -0.4064)
			(stroke
				(width 0.1524)
				(type default)
			)
			(layer "B.SilkS")
		)
		(fp_line
			(start -0.7874 -0.4064)
			(end -0.7874 0.4064)
			(stroke
				(width 0.1524)
				(type default)
			)
			(layer "B.SilkS")
		)
		(fp_line
			(start 0.7874 -0.4064)
			(end -0.7874 -0.4064)
			(stroke
				(width 0.1524)
				(type default)
			)
			(layer "B.SilkS")
		)
		(fp_line
			(start -0.67945 0.3048)
			(end -0.120396 0.3048)
			(stroke
				(width 0.1)
				(type default)
			)
			(layer "B.Fab")
		)
		(fp_line
			(start -0.120396 0.3048)
			(end -0.120396 0.2794)
			(stroke
				(width 0.1)
				(type default)
			)
			(layer "B.Fab")
		)
		(fp_line
			(start 0.12065 0.3048)
			(end 0.67945 0.3048)
			(stroke
				(width 0.1)
				(type default)
			)
			(layer "B.Fab")
		)
		(fp_line
			(start 0.67945 0.3048)
			(end 0.67945 -0.305054)
			(stroke
				(width 0.1)
				(type default)
			)
			(layer "B.Fab")
		)
		(fp_line
			(start -0.120396 0.2794)
			(end 0.12065 0.2794)
			(stroke
				(width 0.1)
				(type default)
			)
			(layer "B.Fab")
		)
		(fp_line
			(start 0.12065 0.2794)
			(end 0.12065 0.3048)
			(stroke
				(width 0.1)
				(type default)
			)
			(layer "B.Fab")
		)
		(fp_line
			(start -0.12065 -0.2794)
			(end -0.12065 -0.3048)
			(stroke
				(width 0.1)
				(type default)
			)
			(layer "B.Fab")
		)
		(fp_line
			(start 0.12065 -0.2794)
			(end -0.12065 -0.2794)
			(stroke
				(width 0.1)
				(type default)
			)
			(layer "B.Fab")
		)
		(fp_line
			(start -0.67945 -0.3048)
			(end -0.67945 0.3048)
			(stroke
				(width 0.1)
				(type default)
			)
			(layer "B.Fab")
		)
		(fp_line
			(start -0.12065 -0.3048)
			(end -0.67945 -0.3048)
			(stroke
				(width 0.1)
				(type default)
			)
			(layer "B.Fab")
		)
		(fp_line
			(start 0.12065 -0.305054)
			(end 0.12065 -0.2794)
			(stroke
				(width 0.1)
				(type default)
			)
			(layer "B.Fab")
		)
		(fp_line
			(start 0.67945 -0.305054)
			(end 0.12065 -0.305054)
			(stroke
				(width 0.1)
				(type default)
			)
			(layer "B.Fab")
		)
		(pad "1" smd circle
			(at 0.40005 0 90)
			(size 0 0)
			(layers "B.Cu" "B.Mask" "B.Paste")
			(net "P3V3_AUX")
		)
		(pad "2" smd circle
			(at -0.40005 0 90)
			(size 0 0)
			(layers "B.Cu" "B.Mask" "B.Paste")
			(net "GPU_FPGA_EROT_FATALERR_ISO_N")
		)
	)
	(footprint ""
		(layer "B.Cu")
		(at 164.900864 -420.184834 90)
		(property "Reference" "R827"
			(at 0 0 90)
			(layer "B.SilkS")
			(hide yes)
			(effects
				(font
					(size 1.27 1.27)
				)
				(justify mirror)
			)
		)
		(property "Value" ""
			(at 0 0 90)
			(layer "B.Fab")
			(effects
				(font
					(size 1.27 1.27)
				)
				(justify mirror)
			)
		)
		(duplicate_pad_numbers_are_jumpers no)
		(fp_line
			(start 0.32512 -0.175006)
			(end -0.32512 -0.175006)
			(stroke
				(width 0.1)
				(type default)
			)
			(layer "B.Fab")
		)
		(fp_line
			(start -0.32512 -0.175006)
			(end -0.32512 0.175006)
			(stroke
				(width 0.1)
				(type default)
			)
			(layer "B.Fab")
		)
		(fp_line
			(start 0.32512 0.175006)
			(end 0.32512 -0.175006)
			(stroke
				(width 0.1)
				(type default)
			)
			(layer "B.Fab")
		)
		(fp_line
			(start -0.32512 0.175006)
			(end 0.32512 0.175006)
			(stroke
				(width 0.1)
				(type default)
			)
			(layer "B.Fab")
		)
		(pad "1" smd rect
			(at 0.2667 0 270)
			(size 0.3048 0.381)
			(layers "B.Cu" "B.Mask" "B.Paste")
			(net "P1V8_CPU1_RT_1D")
		)
		(pad "2" smd rect
			(at -0.2667 0 90)
			(size 0.3048 0.381)
			(layers "B.Cu" "B.Mask" "B.Paste")
			(net "SMB_RT_CPU1_P2_ROM_R_SCL")
		)
	)
)
